# T6G (Grand Teton) — schematic netlist excerpt (pin names and nets, part order shuffled) for the footprints in the layout excerpt that follows; sources: Cadence DE-HDL packaged netlist, KiCad conversion of 04192023_DAF0TMB3IC0_F0TG_MB_C_brd_V02_OCP.brd

R260  Q_RES  0 5% CHIP  pkg 0402LF  page 82 : A = CPU1_SP5R1 ; B = FM_CPU1_SP5R1
C2069  Q_CAP  0.1UF 25V 10% X7R  pkg 0402  page 236 : A = P3V3_E1S_0_R ; B = GND

(kicad_pcb
	(version 20260206)
	(generator "pcbnew")
	(generator_version "10.0")
	(general
		(thickness 1.6)
		(legacy_teardrops no)
	)
	(paper "A4")
	(title_block
		(title "04192023_DAF0TMB3IC0_F0TG_MB_C_brd_V02_OCP.brd")
		(comment 1 "Grand Teton / footprints 7679-7680 of 8354")
	)
	(layers
		(0 "F.Cu" signal "TOP")
		(4 "In1.Cu" signal "GND")
		(6 "In2.Cu" signal "IN1")
		(8 "In3.Cu" signal "GND1")
		(10 "In4.Cu" signal "IN2")
		(12 "In5.Cu" signal "GND2")
		(14 "In6.Cu" signal "IN3")
		(16 "In7.Cu" signal "GND3")
		(18 "In8.Cu" signal "VCC")
		(20 "In9.Cu" signal "VCC1")
		(22 "In10.Cu" signal "GND4")
		(24 "In11.Cu" signal "IN4")
		(26 "In12.Cu" signal "GND5")
		(28 "In13.Cu" signal "IN5")
		(30 "In14.Cu" signal "GND6")
		(32 "In15.Cu" signal "IN6")
		(34 "In16.Cu" signal "GND7")
		(2 "B.Cu" signal "BOTTOM")
		(9 "F.Adhes" user "F.Adhesive")
		(11 "B.Adhes" user "B.Adhesive")
		(13 "F.Paste" user "Package Geometry/Pastemask Top")
		(15 "B.Paste" user "Package Geometry/Pastemask Bottom")
		(5 "F.SilkS" user "Ref Des/Silkscreen Top")
		(7 "B.SilkS" user "Ref Des/Silkscreen Bottom")
		(1 "F.Mask" user "Board Geometry/Soldermask Top")
		(3 "B.Mask" user "Board Geometry/Soldermask Bottom")
		(17 "Dwgs.User" user "User.Drawings")
		(19 "Cmts.User" user "User.Comments")
		(21 "Eco1.User" user "User.Eco1")
		(23 "Eco2.User" user "User.Eco2")
		(25 "Edge.Cuts" user "Board Geometry/Outline")
		(27 "Margin" user)
		(31 "F.CrtYd" user "Package Geometry/Place Bound Top")
		(29 "B.CrtYd" user "Package Geometry/Place Bound Bottom")
		(35 "F.Fab" user "Ref Des/Assembly Top")
		(33 "B.Fab" user "Ref Des/Assembly Bottom")
	)
	(footprint ""
		(layer "B.Cu")
		(at 190.881 -97.119948 -90)
		(property "Reference" "R260"
			(at 0 0 90)
			(layer "B.SilkS")
			(hide yes)
			(effects
				(font
					(size 1.27 1.27)
				)
				(justify mirror)
			)
		)
		(property "Value" ""
			(at 0 0 90)
			(layer "B.Fab")
			(effects
				(font
					(size 1.27 1.27)
				)
				(justify mirror)
			)
		)
		(duplicate_pad_numbers_are_jumpers no)
		(fp_line
			(start -0.7874 0.4064)
			(end 0.7874 0.4064)
			(stroke
				(width 0.1524)
				(type default)
			)
			(layer "B.SilkS")
		)
		(fp_line
			(start 0.7874 0.4064)
			(end 0.7874 -0.4064)
			(stroke
				(width 0.1524)
				(type default)
			)
			(layer "B.SilkS")
		)
		(fp_line
			(start -0.7874 -0.4064)
			(end -0.7874 0.4064)
			(stroke
				(width 0.1524)
				(type default)
			)
			(layer "B.SilkS")
		)
		(fp_line
			(start 0.7874 -0.4064)
			(end -0.7874 -0.4064)
			(stroke
				(width 0.1524)
				(type default)
			)
			(layer "B.SilkS")
		)
		(fp_line
			(start -0.67945 0.3048)
			(end -0.120396 0.3048)
			(stroke
				(width 0.1)
				(type default)
			)
			(layer "B.Fab")
		)
		(fp_line
			(start -0.120396 0.3048)
			(end -0.120396 0.2794)
			(stroke
				(width 0.1)
				(type default)
			)
			(layer "B.Fab")
		)
		(fp_line
			(start 0.12065 0.3048)
			(end 0.67945 0.3048)
			(stroke
				(width 0.1)
				(type default)
			)
			(layer "B.Fab")
		)
		(fp_line
			(start 0.67945 0.3048)
			(end 0.67945 -0.305054)
			(stroke
				(width 0.1)
				(type default)
			)
			(layer "B.Fab")
		)
		(fp_line
			(start -0.120396 0.2794)
			(end 0.12065 0.2794)
			(stroke
				(width 0.1)
				(type default)
			)
			(layer "B.Fab")
		)
		(fp_line
			(start 0.12065 0.2794)
			(end 0.12065 0.3048)
			(stroke
				(width 0.1)
				(type default)
			)
			(layer "B.Fab")
		)
		(fp_line
			(start -0.12065 -0.2794)
			(end -0.12065 -0.3048)
			(stroke
				(width 0.1)
				(type default)
			)
			(layer "B.Fab")
		)
		(fp_line
			(start 0.12065 -0.2794)
			(end -0.12065 -0.2794)
			(stroke
				(width 0.1)
				(type default)
			)
			(layer "B.Fab")
		)
		(fp_line
			(start -0.67945 -0.3048)
			(end -0.67945 0.3048)
			(stroke
				(width 0.1)
				(type default)
			)
			(layer "B.Fab")
		)
		(fp_line
			(start -0.12065 -0.3048)
			(end -0.67945 -0.3048)
			(stroke
				(width 0.1)
				(type default)
			)
			(layer "B.Fab")
		)
		(fp_line
			(start 0.12065 -0.305054)
			(end 0.12065 -0.2794)
			(stroke
				(width 0.1)
				(type default)
			)
			(layer "B.Fab")
		)
		(fp_line
			(start 0.67945 -0.305054)
			(end 0.12065 -0.305054)
			(stroke
				(width 0.1)
				(type default)
			)
			(layer "B.Fab")
		)
		(pad "1" smd circle
			(at 0.40005 0 90)
			(size 0 0)
			(layers "B.Cu" "B.Mask" "B.Paste")
			(net "CPU1_SP5R1")
		)
		(pad "2" smd circle
			(at -0.40005 0 90)
			(size 0 0)
			(layers "B.Cu" "B.Mask" "B.Paste")
			(net "FM_CPU1_SP5R1")
		)
	)
	(footprint ""
		(layer "B.Cu")
		(at 216.18448 -54.955948)
		(property "Reference" "C2069"
			(at 0 0 0)
			(layer "B.SilkS")
			(hide yes)
			(effects
				(font
					(size 1.27 1.27)
				)
				(justify mirror)
			)
		)
		(property "Value" ""
			(at 0 0 0)
			(layer "B.Fab")
			(effects
				(font
					(size 1.27 1.27)
				)
				(justify mirror)
			)
		)
		(duplicate_pad_numbers_are_jumpers no)
		(fp_line
			(start -0.7874 -0.4064)
			(end -0.7874 0.4064)
			(stroke
				(width 0.1524)
				(type default)
			)
			(layer "B.SilkS")
		)
		(fp_line
			(start -0.7874 0.4064)
			(end 0.7874 0.4064)
			(stroke
				(width 0.1524)
				(type default)
			)
			(layer "B.SilkS")
		)
		(fp_line
			(start 0.7874 -0.4064)
			(end -0.7874 -0.4064)
			(stroke
				(width 0.1524)
				(type default)
			)
			(layer "B.SilkS")
		)
		(fp_line
			(start 0.7874 0.4064)
			(end 0.7874 -0.4064)
			(stroke
				(width 0.1524)
				(type default)
			)
			(layer "B.SilkS")
		)
		(fp_line
			(start -0.67945 -0.3048)
			(end -0.67945 0.3048)
			(stroke
				(width 0.1)
				(type default)
			)
			(layer "B.Fab")
		)
		(fp_line
			(start -0.67945 0.3048)
			(end -0.120396 0.3048)
			(stroke
				(width 0.1)
				(type default)
			)
			(layer "B.Fab")
		)
		(fp_line
			(start -0.12065 -0.3048)
			(end -0.67945 -0.3048)
			(stroke
				(width 0.1)
				(type default)
			)
			(layer "B.Fab")
		)
		(fp_line
			(start -0.12065 -0.2794)
			(end -0.12065 -0.3048)
			(stroke
				(width 0.1)
				(type default)
			)
			(layer "B.Fab")
		)
		(fp_line
			(start -0.120396 0.2794)
			(end 0.12065 0.2794)
			(stroke
				(width 0.1)
				(type default)
			)
			(layer "B.Fab")
		)
		(fp_line
			(start -0.120396 0.3048)
			(end -0.120396 0.2794)
			(stroke
				(width 0.1)
				(type default)
			)
			(layer "B.Fab")
		)
		(fp_line
			(start 0.12065 -0.305054)
			(end 0.12065 -0.2794)
			(stroke
				(width 0.1)
				(type default)
			)
			(layer "B.Fab")
		)
		(fp_line
			(start 0.12065 -0.2794)
			(end -0.12065 -0.2794)
			(stroke
				(width 0.1)
				(type default)
			)
			(layer "B.Fab")
		)
		(fp_line
			(start 0.12065 0.2794)
			(end 0.12065 0.3048)
			(stroke
				(width 0.1)
				(type default)
			)
			(layer "B.Fab")
		)
		(fp_line
			(start 0.12065 0.3048)
			(end 0.67945 0.3048)
			(stroke
				(width 0.1)
				(type default)
			)
			(layer "B.Fab")
		)
		(fp_line
			(start 0.67945 -0.305054)
			(end 0.12065 -0.305054)
			(stroke
				(width 0.1)
				(type default)
			)
			(layer "B.Fab")
		)
		(fp_line
			(start 0.67945 0.3048)
			(end 0.67945 -0.305054)
			(stroke
				(width 0.1)
				(type default)
			)
			(layer "B.Fab")
		)
		(pad "1" smd circle
			(at 0.40005 0 180)
			(size 0 0)
			(layers "B.Cu" "B.Mask" "B.Paste")
			(net "P3V3_E1S_0_R")
		)
		(pad "2" smd circle
			(at -0.40005 0 180)
			(size 0 0)
			(layers "B.Cu" "B.Mask" "B.Paste")
			(net "GND")
		)
	)
)
